(kicad_pcb
	(version 20240108)
	(generator "pcbnew")
	(generator_version "8.0")
	(general
		(thickness 1.62)
		(legacy_teardrops no)
	)
	(paper "A4")
	(title_block
		(title "Jetson Orin Baseboard")
		(date "2025-03-12")
		(rev "1.3.4")
		(company "Antmicro Ltd")
		(comment 1 "www.antmicro.com")
		(comment 9 "footprints 676-676 of 677")
	)
	(layers
		(0 "F.Cu" signal)
		(1 "In1.Cu" signal)
		(2 "In2.Cu" signal)
		(3 "In3.Cu" signal)
		(4 "In4.Cu" jumper)
		(5 "In5.Cu" signal)
		(6 "In6.Cu" signal)
		(31 "B.Cu" signal)
		(32 "B.Adhes" user "B.Adhesive")
		(33 "F.Adhes" user "F.Adhesive")
		(34 "B.Paste" user)
		(35 "F.Paste" user)
		(36 "B.SilkS" user "B.Silkscreen")
		(37 "F.SilkS" user "F.Silkscreen")
		(38 "B.Mask" user)
		(39 "F.Mask" user)
		(40 "Dwgs.User" user "User.Drawings")
		(41 "Cmts.User" user "User.Comments")
		(42 "Eco1.User" user "User.Eco1")
		(43 "Eco2.User" user "User.Eco2")
		(44 "Edge.Cuts" user)
		(45 "Margin" user)
		(46 "B.CrtYd" user "B.Courtyard")
		(47 "F.CrtYd" user "F.Courtyard")
		(48 "B.Fab" user)
		(49 "F.Fab" user)
	)
	(footprint "antmicro-footprints:SOT-23-3"
		(layer "B.Cu")
		(at 49.625 80.1)
		(property "Reference" "Q18"
			(at -1.875 -2.925 90)
			(layer "B.SilkS")
			(effects
				(font
					(size 0.7 0.7)
					(thickness 0.15)
				)
				(justify left bottom mirror)
			)
		)
		(property "Value" "SSM3J332R"
			(at -1.9 -2.7 180)
			(layer "B.Fab")
			(effects
				(font
					(size 0.7 0.7)
					(thickness 0.15)
				)
				(justify left bottom mirror)
			)
		)
		(property "Footprint" "antmicro-footprints:SOT-23-3"
			(at 0 0 0)
			(layer "F.Fab")
			(hide yes)
			(effects
				(font
					(size 1.27 1.27)
					(thickness 0.15)
				)
			)
		)
		(property "Datasheet" "https://www.mouser.com/datasheet/2/408/SSM3J332R_datasheet_en_20181015-1150575.pdf"
			(at 0 0 0)
			(layer "F.Fab")
			(hide yes)
			(effects
				(font
					(size 1.27 1.27)
					(thickness 0.15)
				)
			)
		)
		(property "Author" "Antmicro"
			(at 0 0 0)
			(layer "B.Fab")
			(hide yes)
			(effects
				(font
					(size 1 1)
					(thickness 0.15)
				)
				(justify mirror)
			)
		)
		(property "License" "Apache-2.0"
			(at 0 0 0)
			(layer "B.Fab")
			(hide yes)
			(effects
				(font
					(size 1 1)
					(thickness 0.15)
				)
				(justify mirror)
			)
		)
		(property "MPN" "SSM3J332R,LF"
			(at 0 0 0)
			(layer "B.Fab")
			(hide yes)
			(effects
				(font
					(size 1 1)
					(thickness 0.15)
				)
				(justify mirror)
			)
		)
		(property "Manufacturer" "Toshiba"
			(at 0 0 0)
			(layer "B.Fab")
			(hide yes)
			(effects
				(font
					(size 1 1)
					(thickness 0.15)
				)
				(justify mirror)
			)
		)
		(sheetname "Supply")
		(sheetfile "supply.kicad_sch")
		(attr smd)
		(fp_line
			(start -0.85 1.35)
			(end -1.45 1.35)
			(stroke
				(width 0.15)
				(type solid)
			)
			(layer "B.SilkS")
		)
		(fp_line
			(start -0.7 -1.5)
			(end 0.7 -1.5)
			(stroke
				(width 0.15)
				(type solid)
			)
			(layer "B.SilkS")
		)
		(fp_line
			(start -0.7 -1.35)
			(end -0.7 -1.5)
			(stroke
				(width 0.15)
				(type solid)
			)
			(layer "B.SilkS")
		)
		(fp_line
			(start -0.7 1.5)
			(end -0.85 1.35)
			(stroke
				(width 0.15)
				(type solid)
			)
			(layer "B.SilkS")
		)
		(fp_line
			(start -0.7 1.5)
			(end 0.7 1.5)
			(stroke
				(width 0.15)
				(type solid)
			)
			(layer "B.SilkS")
		)
		(fp_line
			(start 0.7 -1.5)
			(end 0.7 -0.4)
			(stroke
				(width 0.15)
				(type solid)
			)
			(layer "B.SilkS")
		)
		(fp_line
			(start 0.7 1.5)
			(end 0.7 0.4)
			(stroke
				(width 0.15)
				(type solid)
			)
			(layer "B.SilkS")
		)
		(fp_line
			(start -1.75 -1.4)
			(end -0.85 -1.4)
			(stroke
				(width 0.05)
				(type solid)
			)
			(layer "B.CrtYd")
		)
		(fp_line
			(start -1.75 -0.5)
			(end -1.75 -1.4)
			(stroke
				(width 0.05)
				(type solid)
			)
			(layer "B.CrtYd")
		)
		(fp_line
			(start -1.75 0.5)
			(end -0.85 0.5)
			(stroke
				(width 0.05)
				(type solid)
			)
			(layer "B.CrtYd")
		)
		(fp_line
			(start -1.75 1.4)
			(end -1.75 0.5)
			(stroke
				(width 0.05)
				(type solid)
			)
			(layer "B.CrtYd")
		)
		(fp_line
			(start -1.75 1.4)
			(end -0.9 1.4)
			(stroke
				(width 0.05)
				(type solid)
			)
			(layer "B.CrtYd")
		)
		(fp_line
			(start -0.9 1.4)
			(end -0.9 1.6)
			(stroke
				(width 0.05)
				(type solid)
			)
			(layer "B.CrtYd")
		)
		(fp_line
			(start -0.85 -1.65)
			(end 0.85 -1.65)
			(stroke
				(width 0.05)
				(type solid)
			)
			(layer "B.CrtYd")
		)
		(fp_line
			(start -0.85 -1.4)
			(end -0.85 -1.65)
			(stroke
				(width 0.05)
				(type solid)
			)
			(layer "B.CrtYd")
		)
		(fp_line
			(start -0.85 -0.5)
			(end -1.75 -0.5)
			(stroke
				(width 0.05)
				(type solid)
			)
			(layer "B.CrtYd")
		)
		(fp_line
			(start -0.85 0.5)
			(end -0.85 -0.5)
			(stroke
				(width 0.05)
				(type solid)
			)
			(layer "B.CrtYd")
		)
		(fp_line
			(start 0.825 0.45)
			(end 0.825 1.6)
			(stroke
				(width 0.05)
				(type solid)
			)
			(layer "B.CrtYd")
		)
		(fp_line
			(start 0.825 1.6)
			(end -0.9 1.6)
			(stroke
				(width 0.05)
				(type solid)
			)
			(layer "B.CrtYd")
		)
		(fp_line
			(start 0.85 -1.65)
			(end 0.85 -0.45)
			(stroke
				(width 0.05)
				(type solid)
			)
			(layer "B.CrtYd")
		)
		(fp_line
			(start 0.85 -0.45)
			(end 1.75 -0.45)
			(stroke
				(width 0.05)
				(type solid)
			)
			(layer "B.CrtYd")
		)
		(fp_line
			(start 1.75 -0.45)
			(end 1.75 0.45)
			(stroke
				(width 0.05)
				(type solid)
			)
			(layer "B.CrtYd")
		)
		(fp_line
			(start 1.75 0.45)
			(end 0.825 0.45)
			(stroke
				(width 0.05)
				(type solid)
			)
			(layer "B.CrtYd")
		)
		(fp_line
			(start -0.712 -1.523)
			(end -0.712 1.325)
			(stroke
				(width 0.15)
				(type solid)
			)
			(layer "B.Fab")
		)
		(fp_line
			(start -0.712 1.325)
			(end -0.437 1.526)
			(stroke
				(width 0.15)
				(type solid)
			)
			(layer "B.Fab")
		)
		(fp_line
			(start 0.688 -1.519)
			(end -0.712 -1.519)
			(stroke
				(width 0.15)
				(type solid)
			)
			(layer "B.Fab")
		)
		(fp_line
			(start 0.688 1.52)
			(end 0.688 -1.519)
			(stroke
				(width 0.15)
				(type solid)
			)
			(layer "B.Fab")
		)
		(fp_line
			(start 0.688 1.526)
			(end -0.437 1.526)
			(stroke
				(width 0.15)
				(type solid)
			)
			(layer "B.Fab")
		)
		(fp_text user "${REFERENCE}"
			(at -1.837 -4 180)
			(layer "B.Fab")
			(hide yes)
			(effects
				(font
					(size 0.7 0.7)
					(thickness 0.15)
				)
				(justify left bottom mirror)
			)
		)
		(fp_text user "Author: Antmicro"
			(at -1.837 -5.3 180)
			(layer "B.Fab")
			(hide yes)
			(effects
				(font
					(size 0.7 0.7)
					(thickness 0.15)
				)
				(justify left bottom mirror)
			)
		)
		(fp_text user "License: Apache-2.0"
			(at -1.8 -6.8 180)
			(layer "B.Fab")
			(hide yes)
			(effects
				(font
					(size 0.7 0.7)
					(thickness 0.15)
				)
				(justify left bottom mirror)
			)
		)
		(pad "1" smd roundrect
			(at -1.1 0.951)
			(size 1 0.6)
			(layers "B.Cu" "B.Paste" "B.Mask")
			(roundrect_rratio 0.15)
			(net 135 "Net-(Q18-G)")
			(pinfunction "G")
			(pintype "bidirectional")
		)
		(pad "2" smd roundrect
			(at -1.1 -0.949)
			(size 1 0.6)
			(layers "B.Cu" "B.Paste" "B.Mask")
			(roundrect_rratio 0.15)
			(net 328 "/Supply/VCC_IN")
			(pinfunction "S")
			(pintype "bidirectional")
		)
		(pad "3" smd roundrect
			(at 1.1 0.0005)
			(size 1 0.6)
			(layers "B.Cu" "B.Paste" "B.Mask")
			(roundrect_rratio 0.15)
			(net 115 "VCC")
			(pinfunction "D")
			(pintype "bidirectional")
		)
	)
)
